# T6G (Grand Teton) — schematic netlist excerpt (pin names and nets, part order shuffled) for the footprints in the layout excerpt that follows; sources: Cadence DE-HDL packaged netlist, KiCad conversion of 04192023_DAF0TMB3IC0_F0TG_MB_C_brd_V02_OCP.brd

PC474_2  Q_CAP  0.1UF 25V 10% X7R  pkg 0402  page 194 : A = PVDDCR_CPU0_P0_VCCS ; B = GND
C756  Q_CAP_DIFFBUS  DIFF BUS_0.22UF 6.3V 20% X6S  pkg C0201  page 66 : \1\ = P5E_CPU1_P2_TX_C_DN<8> ; \2\ = P5E_CPU1_P2_TX_DN<8>

Q30  MOSFET_N_GSD  NX138BK IC  pkg SOT23_GDSXE  page 165
  DRAIN  = LED_BIOS_DBG_MODE_N
  GATE  = BIOS_DEBUG_MODE
  SOURCE  = GND

(kicad_pcb
	(version 20260206)
	(generator "pcbnew")
	(generator_version "10.0")
	(general
		(thickness 1.6)
		(legacy_teardrops no)
	)
	(paper "A4")
	(title_block
		(title "04192023_DAF0TMB3IC0_F0TG_MB_C_brd_V02_OCP.brd")
		(comment 1 "Grand Teton / footprints 4240-4242 of 8354")
	)
	(layers
		(0 "F.Cu" signal "TOP")
		(4 "In1.Cu" signal "GND")
		(6 "In2.Cu" signal "IN1")
		(8 "In3.Cu" signal "GND1")
		(10 "In4.Cu" signal "IN2")
		(12 "In5.Cu" signal "GND2")
		(14 "In6.Cu" signal "IN3")
		(16 "In7.Cu" signal "GND3")
		(18 "In8.Cu" signal "VCC")
		(20 "In9.Cu" signal "VCC1")
		(22 "In10.Cu" signal "GND4")
		(24 "In11.Cu" signal "IN4")
		(26 "In12.Cu" signal "GND5")
		(28 "In13.Cu" signal "IN5")
		(30 "In14.Cu" signal "GND6")
		(32 "In15.Cu" signal "IN6")
		(34 "In16.Cu" signal "GND7")
		(2 "B.Cu" signal "BOTTOM")
		(9 "F.Adhes" user "F.Adhesive")
		(11 "B.Adhes" user "B.Adhesive")
		(13 "F.Paste" user "Package Geometry/Pastemask Top")
		(15 "B.Paste" user "Package Geometry/Pastemask Bottom")
		(5 "F.SilkS" user "Ref Des/Silkscreen Top")
		(7 "B.SilkS" user "Ref Des/Silkscreen Bottom")
		(1 "F.Mask" user "Board Geometry/Soldermask Top")
		(3 "B.Mask" user "Board Geometry/Soldermask Bottom")
		(17 "Dwgs.User" user "User.Drawings")
		(19 "Cmts.User" user "User.Comments")
		(21 "Eco1.User" user "User.Eco1")
		(23 "Eco2.User" user "User.Eco2")
		(25 "Edge.Cuts" user "Board Geometry/Outline")
		(27 "Margin" user)
		(31 "F.CrtYd" user "Package Geometry/Place Bound Top")
		(29 "B.CrtYd" user "Package Geometry/Place Bound Bottom")
		(35 "F.Fab" user "Ref Des/Assembly Top")
		(33 "B.Fab" user "Ref Des/Assembly Bottom")
	)
	(footprint ""
		(layer "F.Cu")
		(at 157.146244 -373.03583 -90)
		(property "Reference" "C756"
			(at 0 0 270)
			(layer "F.SilkS")
			(hide yes)
			(effects
				(font
					(size 1.27 1.27)
				)
			)
		)
		(property "Value" ""
			(at 0 0 270)
			(layer "F.Fab")
			(effects
				(font
					(size 1.27 1.27)
				)
			)
		)
		(duplicate_pad_numbers_are_jumpers no)
		(fp_line
			(start -0.299974 0.150114)
			(end -0.299974 -0.150114)
			(stroke
				(width 0.1)
				(type default)
			)
			(layer "F.Fab")
		)
		(fp_line
			(start 0.299974 0.150114)
			(end -0.299974 0.150114)
			(stroke
				(width 0.1)
				(type default)
			)
			(layer "F.Fab")
		)
		(fp_line
			(start -0.299974 -0.150114)
			(end 0.299974 -0.150114)
			(stroke
				(width 0.1)
				(type default)
			)
			(layer "F.Fab")
		)
		(fp_line
			(start 0.299974 -0.150114)
			(end 0.299974 0.150114)
			(stroke
				(width 0.1)
				(type default)
			)
			(layer "F.Fab")
		)
		(pad "1" smd rect
			(at -0.2667 0 270)
			(size 0.3048 0.381)
			(layers "F.Cu" "F.Mask" "F.Paste")
			(net "P5E_CPU1_P2_TX_C_DN<8>")
		)
		(pad "2" smd rect
			(at 0.2667 0 270)
			(size 0.3048 0.381)
			(layers "F.Cu" "F.Mask" "F.Paste")
			(net "P5E_CPU1_P2_TX_DN<8>")
		)
	)
	(footprint ""
		(layer "F.Cu")
		(at 375.369074 -177.88636 -90)
		(property "Reference" "PC474_2"
			(at 0 0 270)
			(layer "F.SilkS")
			(hide yes)
			(effects
				(font
					(size 1.27 1.27)
				)
			)
		)
		(property "Value" ""
			(at 0 0 270)
			(layer "F.Fab")
			(effects
				(font
					(size 1.27 1.27)
				)
			)
		)
		(duplicate_pad_numbers_are_jumpers no)
		(fp_line
			(start -0.7874 0.4064)
			(end -0.7874 -0.4064)
			(stroke
				(width 0.1524)
				(type default)
			)
			(layer "F.SilkS")
		)
		(fp_line
			(start 0.7874 0.4064)
			(end -0.7874 0.4064)
			(stroke
				(width 0.1524)
				(type default)
			)
			(layer "F.SilkS")
		)
		(fp_line
			(start -0.7874 -0.4064)
			(end 0.7874 -0.4064)
			(stroke
				(width 0.1524)
				(type default)
			)
			(layer "F.SilkS")
		)
		(fp_line
			(start 0.7874 -0.4064)
			(end 0.7874 0.4064)
			(stroke
				(width 0.1524)
				(type default)
			)
			(layer "F.SilkS")
		)
		(fp_line
			(start -0.67945 0.3048)
			(end -0.67945 -0.305054)
			(stroke
				(width 0.1)
				(type default)
			)
			(layer "F.Fab")
		)
		(fp_line
			(start -0.12065 0.3048)
			(end -0.67945 0.3048)
			(stroke
				(width 0.1)
				(type default)
			)
			(layer "F.Fab")
		)
		(fp_line
			(start 0.120396 0.3048)
			(end 0.120396 0.2794)
			(stroke
				(width 0.1)
				(type default)
			)
			(layer "F.Fab")
		)
		(fp_line
			(start 0.67945 0.3048)
			(end 0.120396 0.3048)
			(stroke
				(width 0.1)
				(type default)
			)
			(layer "F.Fab")
		)
		(fp_line
			(start -0.12065 0.2794)
			(end -0.12065 0.3048)
			(stroke
				(width 0.1)
				(type default)
			)
			(layer "F.Fab")
		)
		(fp_line
			(start 0.120396 0.2794)
			(end -0.12065 0.2794)
			(stroke
				(width 0.1)
				(type default)
			)
			(layer "F.Fab")
		)
		(fp_line
			(start -0.12065 -0.2794)
			(end 0.12065 -0.2794)
			(stroke
				(width 0.1)
				(type default)
			)
			(layer "F.Fab")
		)
		(fp_line
			(start 0.12065 -0.2794)
			(end 0.12065 -0.3048)
			(stroke
				(width 0.1)
				(type default)
			)
			(layer "F.Fab")
		)
		(fp_line
			(start 0.12065 -0.3048)
			(end 0.67945 -0.3048)
			(stroke
				(width 0.1)
				(type default)
			)
			(layer "F.Fab")
		)
		(fp_line
			(start 0.67945 -0.3048)
			(end 0.67945 0.3048)
			(stroke
				(width 0.1)
				(type default)
			)
			(layer "F.Fab")
		)
		(fp_line
			(start -0.67945 -0.305054)
			(end -0.12065 -0.305054)
			(stroke
				(width 0.1)
				(type default)
			)
			(layer "F.Fab")
		)
		(fp_line
			(start -0.12065 -0.305054)
			(end -0.12065 -0.2794)
			(stroke
				(width 0.1)
				(type default)
			)
			(layer "F.Fab")
		)
		(pad "1" smd circle
			(at -0.40005 0 270)
			(size 0 0)
			(layers "F.Cu" "F.Mask" "F.Paste")
			(net "PVDDCR_CPU0_P0_VCCS")
		)
		(pad "2" smd circle
			(at 0.40005 0 270)
			(size 0 0)
			(layers "F.Cu" "F.Mask" "F.Paste")
			(net "GND")
		)
	)
	(footprint ""
		(layer "F.Cu")
		(at 336.195416 -24.617172 -90)
		(property "Reference" "Q30"
			(at -2.829052 -0.126492 0)
			(unlocked yes)
			(layer "F.SilkS")
			(effects
				(font
					(size 0.7874 0.5842)
					(thickness 0.1524)
				)
			)
		)
		(property "Value" ""
			(at 0 0 270)
			(layer "F.Fab")
			(effects
				(font
					(size 1.27 1.27)
				)
			)
		)
		(duplicate_pad_numbers_are_jumpers no)
		(fp_line
			(start -1.8796 1.651)
			(end -1.8796 -1.651)
			(stroke
				(width 0.1524)
				(type default)
			)
			(layer "F.SilkS")
		)
		(fp_line
			(start 1.8796 1.651)
			(end -1.8796 1.651)
			(stroke
				(width 0.1524)
				(type default)
			)
			(layer "F.SilkS")
		)
		(fp_line
			(start -1.8796 -1.651)
			(end 1.8796 -1.651)
			(stroke
				(width 0.1524)
				(type default)
			)
			(layer "F.SilkS")
		)
		(fp_line
			(start 1.8796 -1.651)
			(end 1.8796 1.651)
			(stroke
				(width 0.1524)
				(type default)
			)
			(layer "F.SilkS")
		)
		(fp_line
			(start -0.700024 1.500124)
			(end -0.700024 -1.500124)
			(stroke
				(width 0.1)
				(type default)
			)
			(layer "F.Fab")
		)
		(fp_line
			(start 0.700024 1.500124)
			(end -0.700024 1.500124)
			(stroke
				(width 0.1)
				(type default)
			)
			(layer "F.Fab")
		)
		(fp_line
			(start -0.700024 -1.500124)
			(end 0.700024 -1.500124)
			(stroke
				(width 0.1)
				(type default)
			)
			(layer "F.Fab")
		)
		(fp_line
			(start 0.700024 -1.500124)
			(end 0.700024 1.500124)
			(stroke
				(width 0.1)
				(type default)
			)
			(layer "F.Fab")
		)
		(pad "D" smd rect
			(at 1.119886 0 180)
			(size 1.016 1.2192)
			(layers "F.Cu" "F.Mask" "F.Paste")
			(net "LED_BIOS_DBG_MODE_N")
		)
		(pad "G" smd rect
			(at -1.119886 -0.999998 180)
			(size 1.016 1.2192)
			(layers "F.Cu" "F.Mask" "F.Paste")
			(net "BIOS_DEBUG_MODE")
		)
		(pad "S" smd rect
			(at -1.119886 0.999998 180)
			(size 1.016 1.2192)
			(layers "F.Cu" "F.Mask" "F.Paste")
			(net "GND")
		)
	)
)
